# T6G (Grand Teton) — schematic netlist excerpt (pin names and nets, part order shuffled) for the footprints in the layout excerpt that follows; sources: Cadence DE-HDL packaged netlist, KiCad conversion of 04192023_DAF0TMB3IC0_F0TG_MB_C_brd_V02_OCP.brd

PC27  Q_CAP  22UF 16V 20% X6S  pkg C0805  page 225 : A = SW_P12V_AUX_PVDD11_S3_P1_FLT ; B = GND
PR371  Q_RES  2.2 1% CHIP  pkg 0402LF  page 223 : A = PVDDCR_CPU1_P1_PVCC ; B = PVDDIO_P1_VCC3
C448  Q_CAP  1UF 4V 20% X6S  pkg 0201  page 356 : A = P0V9_CPU1_RT3_2A ; B = GND

(kicad_pcb
	(version 20260206)
	(generator "pcbnew")
	(generator_version "10.0")
	(general
		(thickness 1.6)
		(legacy_teardrops no)
	)
	(paper "A4")
	(title_block
		(title "04192023_DAF0TMB3IC0_F0TG_MB_C_brd_V02_OCP.brd")
		(comment 1 "Grand Teton / footprints 5009-5011 of 8354")
	)
	(layers
		(0 "F.Cu" signal "TOP")
		(4 "In1.Cu" signal "GND")
		(6 "In2.Cu" signal "IN1")
		(8 "In3.Cu" signal "GND1")
		(10 "In4.Cu" signal "IN2")
		(12 "In5.Cu" signal "GND2")
		(14 "In6.Cu" signal "IN3")
		(16 "In7.Cu" signal "GND3")
		(18 "In8.Cu" signal "VCC")
		(20 "In9.Cu" signal "VCC1")
		(22 "In10.Cu" signal "GND4")
		(24 "In11.Cu" signal "IN4")
		(26 "In12.Cu" signal "GND5")
		(28 "In13.Cu" signal "IN5")
		(30 "In14.Cu" signal "GND6")
		(32 "In15.Cu" signal "IN6")
		(34 "In16.Cu" signal "GND7")
		(2 "B.Cu" signal "BOTTOM")
		(9 "F.Adhes" user "F.Adhesive")
		(11 "B.Adhes" user "B.Adhesive")
		(13 "F.Paste" user "Package Geometry/Pastemask Top")
		(15 "B.Paste" user "Package Geometry/Pastemask Bottom")
		(5 "F.SilkS" user "Ref Des/Silkscreen Top")
		(7 "B.SilkS" user "Ref Des/Silkscreen Bottom")
		(1 "F.Mask" user "Board Geometry/Soldermask Top")
		(3 "B.Mask" user "Board Geometry/Soldermask Bottom")
		(17 "Dwgs.User" user "User.Drawings")
		(19 "Cmts.User" user "User.Comments")
		(21 "Eco1.User" user "User.Eco1")
		(23 "Eco2.User" user "User.Eco2")
		(25 "Edge.Cuts" user "Board Geometry/Outline")
		(27 "Margin" user)
		(31 "F.CrtYd" user "Package Geometry/Place Bound Top")
		(29 "B.CrtYd" user "Package Geometry/Place Bound Bottom")
		(35 "F.Fab" user "Ref Des/Assembly Top")
		(33 "B.Fab" user "Ref Des/Assembly Bottom")
	)
	(footprint ""
		(layer "B.Cu")
		(at 132.478526 -386.766562 90)
		(property "Reference" "C448"
			(at 0 0 90)
			(layer "B.SilkS")
			(hide yes)
			(effects
				(font
					(size 1.27 1.27)
				)
				(justify mirror)
			)
		)
		(property "Value" ""
			(at 0 0 90)
			(layer "B.Fab")
			(effects
				(font
					(size 1.27 1.27)
				)
				(justify mirror)
			)
		)
		(duplicate_pad_numbers_are_jumpers no)
		(fp_line
			(start 0.299974 -0.150114)
			(end -0.299974 -0.150114)
			(stroke
				(width 0.1)
				(type default)
			)
			(layer "B.Fab")
		)
		(fp_line
			(start -0.299974 -0.150114)
			(end -0.299974 0.150114)
			(stroke
				(width 0.1)
				(type default)
			)
			(layer "B.Fab")
		)
		(fp_line
			(start 0.299974 0.150114)
			(end 0.299974 -0.150114)
			(stroke
				(width 0.1)
				(type default)
			)
			(layer "B.Fab")
		)
		(fp_line
			(start -0.299974 0.150114)
			(end 0.299974 0.150114)
			(stroke
				(width 0.1)
				(type default)
			)
			(layer "B.Fab")
		)
		(pad "1" smd rect
			(at 0.2667 0 270)
			(size 0.3048 0.381)
			(layers "B.Cu" "B.Mask" "B.Paste")
			(net "P0V9_CPU1_RT3_2A")
		)
		(pad "2" smd rect
			(at -0.2667 0 270)
			(size 0.3048 0.381)
			(layers "B.Cu" "B.Mask" "B.Paste")
			(net "GND")
		)
	)
	(footprint ""
		(layer "B.Cu")
		(at 196.064632 -351.201736 90)
		(property "Reference" "PC27"
			(at 0 0 90)
			(layer "B.SilkS")
			(hide yes)
			(effects
				(font
					(size 1.27 1.27)
				)
				(justify mirror)
			)
		)
		(property "Value" ""
			(at 0 0 90)
			(layer "B.Fab")
			(effects
				(font
					(size 1.27 1.27)
				)
				(justify mirror)
			)
		)
		(duplicate_pad_numbers_are_jumpers no)
		(fp_line
			(start 1.524 -0.762)
			(end -1.524 -0.762)
			(stroke
				(width 0.1524)
				(type default)
			)
			(layer "B.SilkS")
		)
		(fp_line
			(start -1.524 -0.762)
			(end -1.524 0.762)
			(stroke
				(width 0.1524)
				(type default)
			)
			(layer "B.SilkS")
		)
		(fp_line
			(start 1.524 0.762)
			(end 1.524 -0.762)
			(stroke
				(width 0.1524)
				(type default)
			)
			(layer "B.SilkS")
		)
		(fp_line
			(start -1.524 0.762)
			(end 1.524 0.762)
			(stroke
				(width 0.1524)
				(type default)
			)
			(layer "B.SilkS")
		)
		(fp_line
			(start 1.1049 -0.724916)
			(end 1.1049 0.724916)
			(stroke
				(width 0.1)
				(type default)
			)
			(layer "B.Fab")
		)
		(fp_line
			(start -1.1049 -0.724916)
			(end 1.1049 -0.724916)
			(stroke
				(width 0.1)
				(type default)
			)
			(layer "B.Fab")
		)
		(fp_line
			(start 1.1049 0.724916)
			(end -1.1049 0.724916)
			(stroke
				(width 0.1)
				(type default)
			)
			(layer "B.Fab")
		)
		(fp_line
			(start -1.1049 0.724916)
			(end -1.1049 -0.724916)
			(stroke
				(width 0.1)
				(type default)
			)
			(layer "B.Fab")
		)
		(pad "1" smd rect
			(at 0.889 0 90)
			(size 1.016 1.27)
			(layers "B.Cu" "B.Mask" "B.Paste")
			(net "SW_P12V_AUX_PVDD11_S3_P1_FLT")
		)
		(pad "2" smd rect
			(at -0.889 0 90)
			(size 1.016 1.27)
			(layers "B.Cu" "B.Mask" "B.Paste")
			(net "GND")
		)
	)
	(footprint ""
		(layer "B.Cu")
		(at 34.570162 -347.780356 -90)
		(property "Reference" "PR371"
			(at 0 0 90)
			(layer "B.SilkS")
			(hide yes)
			(effects
				(font
					(size 1.27 1.27)
				)
				(justify mirror)
			)
		)
		(property "Value" ""
			(at 0 0 90)
			(layer "B.Fab")
			(effects
				(font
					(size 1.27 1.27)
				)
				(justify mirror)
			)
		)
		(duplicate_pad_numbers_are_jumpers no)
		(fp_line
			(start -0.7874 0.4064)
			(end 0.7874 0.4064)
			(stroke
				(width 0.1524)
				(type default)
			)
			(layer "B.SilkS")
		)
		(fp_line
			(start 0.7874 0.4064)
			(end 0.7874 -0.4064)
			(stroke
				(width 0.1524)
				(type default)
			)
			(layer "B.SilkS")
		)
		(fp_line
			(start -0.7874 -0.4064)
			(end -0.7874 0.4064)
			(stroke
				(width 0.1524)
				(type default)
			)
			(layer "B.SilkS")
		)
		(fp_line
			(start 0.7874 -0.4064)
			(end -0.7874 -0.4064)
			(stroke
				(width 0.1524)
				(type default)
			)
			(layer "B.SilkS")
		)
		(fp_line
			(start -0.67945 0.3048)
			(end -0.120396 0.3048)
			(stroke
				(width 0.1)
				(type default)
			)
			(layer "B.Fab")
		)
		(fp_line
			(start -0.120396 0.3048)
			(end -0.120396 0.2794)
			(stroke
				(width 0.1)
				(type default)
			)
			(layer "B.Fab")
		)
		(fp_line
			(start 0.12065 0.3048)
			(end 0.67945 0.3048)
			(stroke
				(width 0.1)
				(type default)
			)
			(layer "B.Fab")
		)
		(fp_line
			(start 0.67945 0.3048)
			(end 0.67945 -0.305054)
			(stroke
				(width 0.1)
				(type default)
			)
			(layer "B.Fab")
		)
		(fp_line
			(start -0.120396 0.2794)
			(end 0.12065 0.2794)
			(stroke
				(width 0.1)
				(type default)
			)
			(layer "B.Fab")
		)
		(fp_line
			(start 0.12065 0.2794)
			(end 0.12065 0.3048)
			(stroke
				(width 0.1)
				(type default)
			)
			(layer "B.Fab")
		)
		(fp_line
			(start -0.12065 -0.2794)
			(end -0.12065 -0.3048)
			(stroke
				(width 0.1)
				(type default)
			)
			(layer "B.Fab")
		)
		(fp_line
			(start 0.12065 -0.2794)
			(end -0.12065 -0.2794)
			(stroke
				(width 0.1)
				(type default)
			)
			(layer "B.Fab")
		)
		(fp_line
			(start -0.67945 -0.3048)
			(end -0.67945 0.3048)
			(stroke
				(width 0.1)
				(type default)
			)
			(layer "B.Fab")
		)
		(fp_line
			(start -0.12065 -0.3048)
			(end -0.67945 -0.3048)
			(stroke
				(width 0.1)
				(type default)
			)
			(layer "B.Fab")
		)
		(fp_line
			(start 0.12065 -0.305054)
			(end 0.12065 -0.2794)
			(stroke
				(width 0.1)
				(type default)
			)
			(layer "B.Fab")
		)
		(fp_line
			(start 0.67945 -0.305054)
			(end 0.12065 -0.305054)
			(stroke
				(width 0.1)
				(type default)
			)
			(layer "B.Fab")
		)
		(pad "1" smd circle
			(at 0.40005 0 90)
			(size 0 0)
			(layers "B.Cu" "B.Mask" "B.Paste")
			(net "PVDDCR_CPU1_P1_PVCC")
		)
		(pad "2" smd circle
			(at -0.40005 0 90)
			(size 0 0)
			(layers "B.Cu" "B.Mask" "B.Paste")
			(net "PVDDIO_P1_VCC3")
		)
	)
)
